(kicad_pcb
	(version 20260206)
	(generator "pcbnew")
	(generator_version "10.0")
	(general
		(thickness 1.6)
		(legacy_teardrops no)
	)
	(paper "A4")
	(title_block
		(title "v1-chassis-manager — T6M_CM_d_v01_1031_1645.brd")
		(comment 1 "Open CloudServer (Microsoft) / footprints 1102-1106 of 2512")
	)
	(layers
		(0 "F.Cu" signal "TOP")
		(4 "In1.Cu" signal "GND1")
		(6 "In2.Cu" signal "IN1")
		(8 "In3.Cu" signal "VCC1")
		(10 "In4.Cu" signal "VCC2")
		(12 "In5.Cu" signal "GND2")
		(14 "In6.Cu" signal "IN2")
		(16 "In7.Cu" signal "IN3")
		(18 "In8.Cu" signal "GND3")
		(2 "B.Cu" signal "BOTTOM")
		(9 "F.Adhes" user "F.Adhesive")
		(11 "B.Adhes" user "B.Adhesive")
		(13 "F.Paste" user "Package Geometry/Pastemask Top")
		(15 "B.Paste" user "Package Geometry/Pastemask Bottom")
		(5 "F.SilkS" user "Ref Des/Silkscreen Top")
		(7 "B.SilkS" user "Ref Des/Silkscreen Bottom")
		(1 "F.Mask" user "Board Geometry/Soldermask Top")
		(3 "B.Mask" user "Board Geometry/Soldermask Bottom")
		(17 "Dwgs.User" user "User.Drawings")
		(19 "Cmts.User" user "User.Comments")
		(21 "Eco1.User" user "User.Eco1")
		(23 "Eco2.User" user "User.Eco2")
		(25 "Edge.Cuts" user "Board Geometry/Outline")
		(27 "Margin" user)
		(31 "F.CrtYd" user "Package Geometry/Place Bound Top")
		(29 "B.CrtYd" user "Package Geometry/Place Bound Bottom")
		(35 "F.Fab" user "Ref Des/Assembly Top")
		(33 "B.Fab" user "Ref Des/Assembly Bottom")
	)
	(footprint ""
		(layer "F.Cu")
		(at 179.999894 -7.799832)
		(property "Reference" "D19"
			(at 2.5781 -1.85674 90)
			(unlocked yes)
			(layer "F.SilkS")
			(effects
				(font
					(size 0.7874 0.5842)
					(thickness 0.1524)
				)
				(justify left)
			)
		)
		(property "Value" ""
			(at 0 0 0)
			(layer "F.Fab")
			(effects
				(font
					(size 1.27 1.27)
				)
			)
		)
		(duplicate_pad_numbers_are_jumpers no)
		(fp_line
			(start -3.109976 -1.400048)
			(end -3.109976 1.1938)
			(stroke
				(width 0.1524)
				(type default)
			)
			(layer "F.SilkS")
		)
		(fp_line
			(start -3.109976 0.8128)
			(end -3.109976 7.739888)
			(stroke
				(width 0.1524)
				(type default)
			)
			(layer "F.SilkS")
		)
		(fp_line
			(start -3.109976 7.739888)
			(end -2.499868 7.739888)
			(stroke
				(width 0.1524)
				(type default)
			)
			(layer "F.SilkS")
		)
		(fp_line
			(start -2.499868 7.739888)
			(end -2.499868 10.24001)
			(stroke
				(width 0.1524)
				(type default)
			)
			(layer "F.SilkS")
		)
		(fp_line
			(start 2.499868 7.739888)
			(end 3.109976 7.739888)
			(stroke
				(width 0.1524)
				(type default)
			)
			(layer "F.SilkS")
		)
		(fp_line
			(start 2.499868 10.24001)
			(end 2.499868 7.739888)
			(stroke
				(width 0.1524)
				(type default)
			)
			(layer "F.SilkS")
		)
		(fp_line
			(start 3.109976 -1.400048)
			(end -3.109976 -1.400048)
			(stroke
				(width 0.1524)
				(type default)
			)
			(layer "F.SilkS")
		)
		(fp_line
			(start 3.109976 1.4478)
			(end 3.109976 -1.400048)
			(stroke
				(width 0.1524)
				(type default)
			)
			(layer "F.SilkS")
		)
		(fp_line
			(start 3.109976 7.739888)
			(end 3.109976 0.6096)
			(stroke
				(width 0.1524)
				(type default)
			)
			(layer "F.SilkS")
		)
		(fp_arc
			(start 2.499868 10.24001)
			(mid 0 12.739878)
			(end -2.499868 10.24001)
			(stroke
				(width 0.1524)
				(type default)
			)
			(layer "F.SilkS")
		)
		(fp_poly
			(pts
				(xy -1.27 -1.5494) (xy -1.778 -2.5654) (xy -0.762 -2.5654)
			)
			(stroke
				(width 0)
				(type default)
			)
			(fill yes)
			(layer "F.SilkS")
		)
		(fp_poly
			(pts
				(xy -2.0828 3.354832) (xy -2.0828 1.729232) (xy -1.4478 1.729232) (xy -1.4478 1.725168) (xy -0.4572 1.725168)
				(xy -0.4572 3.3528) (xy -1.388872 3.3528) (xy -1.388872 3.354832)
			)
			(stroke
				(width 0)
				(type default)
			)
			(fill no)
			(layer "B.CrtYd")
		)
		(fp_poly
			(pts
				(arc
					(start 0 0.8128)
					(mid 0 -0.8128)
					(end 0 0.8128)
				)
			)
			(stroke
				(width 0)
				(type default)
			)
			(fill no)
			(layer "B.CrtYd")
		)
		(fp_poly
			(pts
				(arc
					(start 1.27 3.3528)
					(mid 1.27 1.7272)
					(end 1.27 3.3528)
				)
			)
			(stroke
				(width 0)
				(type default)
			)
			(fill no)
			(layer "B.CrtYd")
		)
		(fp_poly
			(pts
				(xy -2.499868 7.739888)
				(arc
					(start -2.499868 10.24001)
					(mid 0 12.739878)
					(end 2.499868 10.24001)
				)
				(xy 2.499868 7.739888) (xy 3.109976 7.739888) (xy 3.109976 -1.400048) (xy -3.109976 -1.400048) (xy -3.109976 7.739888)
			)
			(stroke
				(width 0)
				(type default)
			)
			(fill no)
			(layer "F.CrtYd")
		)
		(fp_line
			(start -3.109976 -1.400048)
			(end -3.109976 7.739888)
			(stroke
				(width 0.1)
				(type default)
			)
			(layer "F.Fab")
		)
		(fp_line
			(start -3.109976 -1.400048)
			(end -3.109976 7.739888)
			(stroke
				(width 0.1)
				(type default)
			)
			(layer "F.Fab")
		)
		(fp_line
			(start -3.109976 7.739888)
			(end -2.499868 7.739888)
			(stroke
				(width 0.1)
				(type default)
			)
			(layer "F.Fab")
		)
		(fp_line
			(start -3.109976 7.739888)
			(end -2.499868 7.739888)
			(stroke
				(width 0.1)
				(type default)
			)
			(layer "F.Fab")
		)
		(fp_line
			(start -2.499868 7.739888)
			(end -2.499868 10.24001)
			(stroke
				(width 0.1)
				(type default)
			)
			(layer "F.Fab")
		)
		(fp_line
			(start -2.499868 7.739888)
			(end -2.499868 10.24001)
			(stroke
				(width 0.1)
				(type default)
			)
			(layer "F.Fab")
		)
		(fp_line
			(start 2.499868 7.739888)
			(end 3.109976 7.739888)
			(stroke
				(width 0.1)
				(type default)
			)
			(layer "F.Fab")
		)
		(fp_line
			(start 2.499868 7.739888)
			(end 3.109976 7.739888)
			(stroke
				(width 0.1)
				(type default)
			)
			(layer "F.Fab")
		)
		(fp_line
			(start 2.499868 10.24001)
			(end 2.499868 7.739888)
			(stroke
				(width 0.1)
				(type default)
			)
			(layer "F.Fab")
		)
		(fp_line
			(start 2.499868 10.24001)
			(end 2.499868 7.739888)
			(stroke
				(width 0.1)
				(type default)
			)
			(layer "F.Fab")
		)
		(fp_line
			(start 3.109976 -1.400048)
			(end -3.109976 -1.400048)
			(stroke
				(width 0.1)
				(type default)
			)
			(layer "F.Fab")
		)
		(fp_line
			(start 3.109976 -1.400048)
			(end -3.109976 -1.400048)
			(stroke
				(width 0.1)
				(type default)
			)
			(layer "F.Fab")
		)
		(fp_line
			(start 3.109976 7.739888)
			(end 3.109976 -1.400048)
			(stroke
				(width 0.1)
				(type default)
			)
			(layer "F.Fab")
		)
		(fp_line
			(start 3.109976 7.739888)
			(end 3.109976 -1.400048)
			(stroke
				(width 0.1)
				(type default)
			)
			(layer "F.Fab")
		)
		(fp_arc
			(start 2.499868 10.24001)
			(mid 0 12.739878)
			(end -2.499868 10.24001)
			(stroke
				(width 0.1)
				(type default)
			)
			(layer "F.Fab")
		)
		(fp_arc
			(start 2.499868 10.24001)
			(mid 0 12.739878)
			(end -2.499868 10.24001)
			(stroke
				(width 0.1)
				(type default)
			)
			(layer "F.Fab")
		)
		(fp_poly
			(pts
				(xy -1.27 -1.5494) (xy -1.778 -2.5654) (xy -0.762 -2.5654)
			)
			(stroke
				(width 0)
				(type default)
			)
			(fill yes)
			(layer "F.Fab")
		)
		(fp_text user "1"
			(at -3.706622 1.747266 0)
			(unlocked yes)
			(layer "F.SilkS")
			(effects
				(font
					(size 0.635 0.4064)
					(thickness 0.1524)
				)
				(justify left)
			)
		)
		(fp_text user "2"
			(at -3.705606 -0.309372 0)
			(unlocked yes)
			(layer "F.SilkS")
			(effects
				(font
					(size 0.635 0.4064)
					(thickness 0.1524)
				)
				(justify left)
			)
		)
		(fp_text user "3"
			(at 3.406902 2.565146 0)
			(unlocked yes)
			(layer "F.SilkS")
			(effects
				(font
					(size 0.635 0.4064)
					(thickness 0.1524)
				)
				(justify left)
			)
		)
		(fp_text user "1"
			(at -2.788666 2.29489 0)
			(unlocked yes)
			(layer "B.SilkS")
			(effects
				(font
					(size 0.7874 0.5842)
					(thickness 0.1524)
				)
				(justify left mirror)
			)
		)
		(fp_text user "2"
			(at 0.339344 -1.849882 0)
			(unlocked yes)
			(layer "B.SilkS")
			(effects
				(font
					(size 0.7874 0.5842)
					(thickness 0.1524)
				)
				(justify left mirror)
			)
		)
		(fp_text user "3"
			(at 2.338324 0.907288 0)
			(unlocked yes)
			(layer "B.SilkS")
			(effects
				(font
					(size 0.7874 0.5842)
					(thickness 0.1524)
				)
				(justify left mirror)
			)
		)
		(fp_text user "1"
			(at -0.9779 1.330706 0)
			(unlocked yes)
			(layer "B.Fab")
			(effects
				(font
					(size 0.7874 0.5842)
					(thickness 0.000001)
				)
				(justify left mirror)
			)
		)
		(fp_text user "2"
			(at 0.2921 1.254506 0)
			(unlocked yes)
			(layer "B.Fab")
			(effects
				(font
					(size 0.7874 0.5842)
					(thickness 0.000001)
				)
				(justify left mirror)
			)
		)
		(fp_text user "3"
			(at 1.5621 1.330706 0)
			(unlocked yes)
			(layer "B.Fab")
			(effects
				(font
					(size 0.7874 0.5842)
					(thickness 0.000001)
				)
				(justify left mirror)
			)
		)
		(fp_text user "1"
			(at -2.1717 -2.022094 0)
			(unlocked yes)
			(layer "F.Fab")
			(effects
				(font
					(size 0.7874 0.5842)
					(thickness 0.000001)
				)
				(justify left)
			)
		)
		(fp_text user "2"
			(at -0.2921 -2.022094 0)
			(unlocked yes)
			(layer "F.Fab")
			(effects
				(font
					(size 0.7874 0.5842)
					(thickness 0.000001)
				)
				(justify left)
			)
		)
		(fp_text user "3"
			(at 0.9779 -1.996694 0)
			(unlocked yes)
			(layer "F.Fab")
			(effects
				(font
					(size 0.7874 0.5842)
					(thickness 0.000001)
				)
				(justify left)
			)
		)
		(pad "1" thru_hole rect
			(at -1.27 2.54)
			(size 1.524 1.524)
			(drill 1.016)
			(layers "*.Cu" "*.Mask")
			(remove_unused_layers no)
			(net "CM_STATUS_LED_R")
			(clearance 0)
			(padstack
				(mode front_inner_back)
				(layer "Inner"
					(shape circle)
					(size 1.524 1.524)
					(clearance 0)
				)
				(layer "B.Cu"
					(shape rect)
					(size 1.524 1.524)
					(clearance 0)
				)
			)
		)
		(pad "2" thru_hole circle
			(at 0 0)
			(size 1.524 1.524)
			(drill 1.016)
			(layers "*.Cu" "*.Mask")
			(remove_unused_layers no)
			(net "N53608970")
			(clearance 0)
		)
		(pad "3" thru_hole circle
			(at 1.27 2.54)
			(size 1.524 1.524)
			(drill 1.016)
			(layers "*.Cu" "*.Mask")
			(remove_unused_layers no)
			(net "LED_PWR_GD")
			(clearance 0)
		)
	)
	(footprint ""
		(layer "F.Cu")
		(at 50.337466 -10.963402 90)
		(property "Reference" "PL7"
			(at 4.175252 -4.137406 0)
			(unlocked yes)
			(layer "F.SilkS")
			(effects
				(font
					(size 0.7874 0.5842)
					(thickness 0.1524)
				)
				(justify left)
			)
		)
		(property "Value" ""
			(at 0 0 90)
			(layer "F.Fab")
			(effects
				(font
					(size 1.27 1.27)
				)
			)
		)
		(duplicate_pad_numbers_are_jumpers no)
		(fp_line
			(start 3.350006 -4.1656)
			(end 3.350006 4.1656)
			(stroke
				(width 0.1524)
				(type default)
			)
			(layer "F.SilkS")
		)
		(fp_line
			(start -3.350006 -4.1656)
			(end 3.350006 -4.1656)
			(stroke
				(width 0.1524)
				(type default)
			)
			(layer "F.SilkS")
		)
		(fp_line
			(start 3.350006 4.1656)
			(end -3.350006 4.1656)
			(stroke
				(width 0.1524)
				(type default)
			)
			(layer "F.SilkS")
		)
		(fp_line
			(start -3.350006 4.1656)
			(end -3.350006 -4.1656)
			(stroke
				(width 0.1524)
				(type default)
			)
			(layer "F.SilkS")
		)
		(fp_poly
			(pts
				(xy -3.350006 -3.64998) (xy -1.7018 -3.64998) (xy -1.7018 -4.05257) (xy 1.7018 -4.05257) (xy 1.7018 -3.64998)
				(xy 3.350006 -3.64998) (xy 3.350006 3.64998) (xy 1.7018 3.64998) (xy 1.7018 4.05257) (xy -1.7018 4.05257)
				(xy -1.7018 3.64998) (xy -3.350006 3.64998)
			)
			(stroke
				(width 0)
				(type default)
			)
			(fill no)
			(layer "F.CrtYd")
		)
		(fp_line
			(start 3.350006 -3.64998)
			(end 3.350006 3.64998)
			(stroke
				(width 0.1)
				(type default)
			)
			(layer "F.Fab")
		)
		(fp_line
			(start -3.350006 -3.64998)
			(end 3.350006 -3.64998)
			(stroke
				(width 0.1)
				(type default)
			)
			(layer "F.Fab")
		)
		(fp_line
			(start 3.350006 3.64998)
			(end -3.350006 3.64998)
			(stroke
				(width 0.1)
				(type default)
			)
			(layer "F.Fab")
		)
		(fp_line
			(start -3.350006 3.64998)
			(end -3.350006 -3.64998)
			(stroke
				(width 0.1)
				(type default)
			)
			(layer "F.Fab")
		)
		(pad "1" smd rect
			(at 0 -2.92481)
			(size 2.15392 3.302)
			(layers "F.Cu" "F.Mask" "F.Paste")
			(net "SW_PV_VDDR_NODE1_PH")
		)
		(pad "2" smd rect
			(at 0 2.92481)
			(size 2.15392 3.302)
			(layers "F.Cu" "F.Mask" "F.Paste")
			(net "PV_VDDR_NODE1")
		)
	)
	(footprint ""
		(layer "F.Cu")
		(at 11.12012 -3.705352 180)
		(property "Reference" "R471"
			(at 1.137412 -2.360422 0)
			(unlocked yes)
			(layer "F.SilkS")
			(effects
				(font
					(size 0.7874 0.5842)
					(thickness 0.1524)
				)
				(justify left)
			)
		)
		(property "Value" ""
			(at 0 0 180)
			(layer "F.Fab")
			(effects
				(font
					(size 1.27 1.27)
				)
			)
		)
		(duplicate_pad_numbers_are_jumpers no)
		(fp_line
			(start 0.7874 0.4064)
			(end -0.7874 0.4064)
			(stroke
				(width 0.1524)
				(type default)
			)
			(layer "F.SilkS")
		)
		(fp_line
			(start 0.7874 -0.4064)
			(end 0.7874 0.4064)
			(stroke
				(width 0.1524)
				(type default)
			)
			(layer "F.SilkS")
		)
		(fp_line
			(start -0.7874 0.4064)
			(end -0.7874 -0.4064)
			(stroke
				(width 0.1524)
				(type default)
			)
			(layer "F.SilkS")
		)
		(fp_line
			(start -0.7874 -0.4064)
			(end 0.7874 -0.4064)
			(stroke
				(width 0.1524)
				(type default)
			)
			(layer "F.SilkS")
		)
		(fp_poly
			(pts
				(xy -0.508 0.2794) (xy -0.508 0.2286) (xy -0.635 0.2286) (xy -0.635 -0.254) (xy -0.5334 -0.254)
				(xy -0.5334 -0.2794) (xy 0.5334 -0.2794) (xy 0.5334 -0.254) (xy 0.635 -0.254) (xy 0.635 0.254) (xy 0.5334 0.254)
				(xy 0.5334 0.2794)
			)
			(stroke
				(width 0)
				(type default)
			)
			(fill no)
			(layer "F.CrtYd")
		)
		(pad "1" smd rect
			(at 0.40005 0 180)
			(size 0.4572 0.508)
			(layers "F.Cu" "F.Mask" "F.Paste")
			(net "SMB_MUX_CPU_ICS_NODE1_CLK")
		)
		(pad "2" smd rect
			(at -0.40005 0 180)
			(size 0.4572 0.508)
			(layers "F.Cu" "F.Mask" "F.Paste")
			(net "SMB_DIMM_NODE1_CLK")
		)
	)
	(footprint ""
		(layer "F.Cu")
		(at 52.655978 -170.630088 180)
		(property "Reference" "C618"
			(at 9.03986 -131.070096 0)
			(unlocked yes)
			(layer "F.SilkS")
			(effects
				(font
					(size 0.7874 0.5842)
					(thickness 0.1524)
				)
				(justify left)
			)
		)
		(property "Value" ""
			(at 0 0 180)
			(layer "F.Fab")
			(effects
				(font
					(size 1.27 1.27)
				)
			)
		)
		(duplicate_pad_numbers_are_jumpers no)
		(fp_line
			(start 0.7874 0.4064)
			(end -0.7874 0.4064)
			(stroke
				(width 0.1524)
				(type default)
			)
			(layer "F.SilkS")
		)
		(fp_line
			(start 0.7874 -0.4064)
			(end 0.7874 0.4064)
			(stroke
				(width 0.1524)
				(type default)
			)
			(layer "F.SilkS")
		)
		(fp_line
			(start 0 0.381)
			(end 0 -0.381)
			(stroke
				(width 0.1524)
				(type default)
			)
			(layer "F.SilkS")
		)
		(fp_line
			(start -0.7874 0.4064)
			(end -0.7874 -0.4064)
			(stroke
				(width 0.1524)
				(type default)
			)
			(layer "F.SilkS")
		)
		(fp_line
			(start -0.7874 -0.4064)
			(end 0.7874 -0.4064)
			(stroke
				(width 0.1524)
				(type default)
			)
			(layer "F.SilkS")
		)
		(fp_poly
			(pts
				(xy -0.5334 0.254) (xy -0.635 0.254) (xy -0.635 0.2286) (xy -0.635 -0.254) (xy -0.5334 -0.254) (xy -0.5334 -0.2794)
				(xy 0.5334 -0.2794) (xy 0.5334 -0.254) (xy 0.635 -0.254) (xy 0.635 0.254) (xy 0.5334 0.254) (xy 0.5334 0.2794)
				(xy -0.508 0.2794) (xy -0.5334 0.2794)
			)
			(stroke
				(width 0)
				(type default)
			)
			(fill no)
			(layer "F.CrtYd")
		)
		(pad "1" smd rect
			(at 0.40005 0 180)
			(size 0.4572 0.508)
			(layers "F.Cu" "F.Mask" "F.Paste")
			(net "P3V3_NODE1")
		)
		(pad "2" smd rect
			(at -0.40005 0 180)
			(size 0.4572 0.508)
			(layers "F.Cu" "F.Mask" "F.Paste")
			(net "GND")
		)
	)
	(footprint ""
		(layer "F.Cu")
		(at 127.63246 -53.928518 -90)
		(property "Reference" "U136"
			(at -4.225036 -1.370584 0)
			(unlocked yes)
			(layer "F.SilkS")
			(effects
				(font
					(size 0.7874 0.5842)
					(thickness 0.1524)
				)
			)
		)
		(property "Value" ""
			(at 0 0 270)
			(layer "F.Fab")
			(effects
				(font
					(size 1.27 1.27)
				)
			)
		)
		(duplicate_pad_numbers_are_jumpers no)
		(fp_line
			(start 1.1176 1.7018)
			(end -1.1176 1.7018)
			(stroke
				(width 0.1524)
				(type default)
			)
			(layer "F.SilkS")
		)
		(fp_line
			(start -1.1176 0.254)
			(end -1.1176 1.7018)
			(stroke
				(width 0.1524)
				(type default)
			)
			(layer "F.SilkS")
		)
		(fp_line
			(start -0.7112 0)
			(end -1.1176 0.254)
			(stroke
				(width 0.1524)
				(type default)
			)
			(layer "F.SilkS")
		)
		(fp_line
			(start -1.1176 -0.254)
			(end -0.7112 0)
			(stroke
				(width 0.1524)
				(type default)
			)
			(layer "F.SilkS")
		)
		(fp_line
			(start -1.1176 -1.7018)
			(end -1.1176 -0.254)
			(stroke
				(width 0.1524)
				(type default)
			)
			(layer "F.SilkS")
		)
		(fp_line
			(start -1.1176 -1.7018)
			(end 1.1176 -1.7018)
			(stroke
				(width 0.1524)
				(type default)
			)
			(layer "F.SilkS")
		)
		(fp_line
			(start 1.1176 -1.7018)
			(end 1.1176 1.7018)
			(stroke
				(width 0.1524)
				(type default)
			)
			(layer "F.SilkS")
		)
		(fp_poly
			(pts
				(xy -1.029716 1.566164) (xy -1.281176 2.140712) (xy -1.586484 1.835404)
			)
			(stroke
				(width 0)
				(type default)
			)
			(fill yes)
			(layer "F.SilkS")
		)
		(fp_rect
			(start -1.1176 1.5494)
			(end 1.1176 -1.5494)
			(stroke
				(width 0)
				(type default)
			)
			(fill no)
			(layer "F.CrtYd")
		)
		(fp_line
			(start 1.1176 1.5494)
			(end -1.1176 1.5494)
			(stroke
				(width 0.1)
				(type default)
			)
			(layer "F.Fab")
		)
		(fp_line
			(start -1.1176 0.254)
			(end -1.1176 1.5494)
			(stroke
				(width 0.1)
				(type default)
			)
			(layer "F.Fab")
		)
		(fp_line
			(start -1.1176 -0.254)
			(end -1.1176 0.254)
			(stroke
				(width 0.1)
				(type default)
			)
			(layer "F.Fab")
		)
		(fp_line
			(start -1.1176 -1.5494)
			(end -1.1176 -0.254)
			(stroke
				(width 0.1)
				(type default)
			)
			(layer "F.Fab")
		)
		(fp_line
			(start -1.1176 -1.5494)
			(end 1.1176 -1.5494)
			(stroke
				(width 0.1)
				(type default)
			)
			(layer "F.Fab")
		)
		(fp_line
			(start 1.1176 -1.5494)
			(end 1.1176 1.5494)
			(stroke
				(width 0.1)
				(type default)
			)
			(layer "F.Fab")
		)
		(fp_poly
			(pts
				(xy -0.675386 1.8161) (xy -0.446786 2.4003) (xy -0.878586 2.4003)
			)
			(stroke
				(width 0)
				(type default)
			)
			(fill yes)
			(layer "F.Fab")
		)
		(pad "1" smd rect
			(at -0.649986 0.962406 270)
			(size 0.3302 1.1684)
			(layers "F.Cu" "F.Mask" "F.Paste")
			(net "COM4_EN_N")
		)
		(pad "2" smd rect
			(at 0 0.962406 270)
			(size 0.3302 1.1684)
			(layers "F.Cu" "F.Mask" "F.Paste")
			(net "UART_RX_P4")
		)
		(pad "3" smd rect
			(at 0.649986 0.962406 270)
			(size 0.3302 1.1684)
			(layers "F.Cu" "F.Mask" "F.Paste")
			(net "GND")
		)
		(pad "4" smd rect
			(at 0.649986 -0.962406 270)
			(size 0.3302 1.1684)
			(layers "F.Cu" "F.Mask" "F.Paste")
			(net "UART_RX_P4_BUF")
		)
		(pad "5" smd rect
			(at -0.649986 -0.962406 270)
			(size 0.3302 1.1684)
			(layers "F.Cu" "F.Mask" "F.Paste")
			(net "P3V3_NODE1")
		)
	)
)
